# S9S_MB_2U (Grand Teton) — schematic netlist excerpt (pin names and nets, part order shuffled) for the footprints in the layout excerpt that follows; sources: Cadence DE-HDL packaged netlist, KiCad conversion of 03242023_DA0F0TMBIJ0_F0T_Motherboard_J_brd_V01_OCP.brd

R691  Q_RES  0 5% CHIP  pkg 0402LF  page 229 : A = I3C_SPD_DDRABCD_CPU0_LVC1_R_SCL ; B = I3C_SPD_DDRABCD_CPU0_LVC1_SCL
PR328  Q_RES  2.2 1% CHIP  pkg 0402LF  page 285 : A = PVCCIN_CPU1_PVCC ; B = PVCCIN_CPU1_VDD1

(kicad_pcb
	(version 20260206)
	(generator "pcbnew")
	(generator_version "10.0")
	(general
		(thickness 1.6)
		(legacy_teardrops no)
	)
	(paper "A4")
	(title_block
		(title "03242023_DA0F0TMBIJ0_F0T_Motherboard_J_brd_V01_OCP.brd")
		(comment 1 "Grand Teton / footprints 4650-4651 of 6105")
	)
	(layers
		(0 "F.Cu" signal "TOP")
		(4 "In1.Cu" signal "GND")
		(6 "In2.Cu" signal "IN1")
		(8 "In3.Cu" signal "GND1")
		(10 "In4.Cu" signal "IN2")
		(12 "In5.Cu" signal "GND2")
		(14 "In6.Cu" signal "IN3")
		(16 "In7.Cu" signal "GND3")
		(18 "In8.Cu" signal "VCC")
		(20 "In9.Cu" signal "VCC1")
		(22 "In10.Cu" signal "GND4")
		(24 "In11.Cu" signal "IN4")
		(26 "In12.Cu" signal "GND5")
		(28 "In13.Cu" signal "IN5")
		(30 "In14.Cu" signal "GND6")
		(32 "In15.Cu" signal "IN6")
		(34 "In16.Cu" signal "GND7")
		(2 "B.Cu" signal "BOTTOM")
		(9 "F.Adhes" user "F.Adhesive")
		(11 "B.Adhes" user "B.Adhesive")
		(13 "F.Paste" user "Package Geometry/Pastemask Top")
		(15 "B.Paste" user "Package Geometry/Pastemask Bottom")
		(5 "F.SilkS" user "Ref Des/Silkscreen Top")
		(7 "B.SilkS" user "Ref Des/Silkscreen Bottom")
		(1 "F.Mask" user "Board Geometry/Soldermask Top")
		(3 "B.Mask" user "Board Geometry/Soldermask Bottom")
		(17 "Dwgs.User" user "User.Drawings")
		(19 "Cmts.User" user "User.Comments")
		(21 "Eco1.User" user "User.Eco1")
		(23 "Eco2.User" user "User.Eco2")
		(25 "Edge.Cuts" user "Board Geometry/Outline")
		(27 "Margin" user)
		(31 "F.CrtYd" user "Package Geometry/Place Bound Top")
		(29 "B.CrtYd" user "Package Geometry/Place Bound Bottom")
		(35 "F.Fab" user "Ref Des/Assembly Top")
		(33 "B.Fab" user "Ref Des/Assembly Bottom")
	)
	(footprint ""
		(layer "B.Cu")
		(at 94.596712 -334.752442 -90)
		(property "Reference" "PR328"
			(at 0 0 90)
			(layer "B.SilkS")
			(hide yes)
			(effects
				(font
					(size 1.27 1.27)
				)
				(justify mirror)
			)
		)
		(property "Value" ""
			(at 0 0 90)
			(layer "B.Fab")
			(effects
				(font
					(size 1.27 1.27)
				)
				(justify mirror)
			)
		)
		(duplicate_pad_numbers_are_jumpers no)
		(fp_line
			(start -0.7874 0.4064)
			(end 0.7874 0.4064)
			(stroke
				(width 0.1524)
				(type default)
			)
			(layer "B.SilkS")
		)
		(fp_line
			(start 0.7874 0.4064)
			(end 0.7874 -0.4064)
			(stroke
				(width 0.1524)
				(type default)
			)
			(layer "B.SilkS")
		)
		(fp_line
			(start -0.7874 -0.4064)
			(end -0.7874 0.4064)
			(stroke
				(width 0.1524)
				(type default)
			)
			(layer "B.SilkS")
		)
		(fp_line
			(start 0.7874 -0.4064)
			(end -0.7874 -0.4064)
			(stroke
				(width 0.1524)
				(type default)
			)
			(layer "B.SilkS")
		)
		(fp_line
			(start -0.67945 0.3048)
			(end -0.120396 0.3048)
			(stroke
				(width 0.1)
				(type default)
			)
			(layer "B.Fab")
		)
		(fp_line
			(start -0.120396 0.3048)
			(end -0.120396 0.2794)
			(stroke
				(width 0.1)
				(type default)
			)
			(layer "B.Fab")
		)
		(fp_line
			(start 0.12065 0.3048)
			(end 0.67945 0.3048)
			(stroke
				(width 0.1)
				(type default)
			)
			(layer "B.Fab")
		)
		(fp_line
			(start 0.67945 0.3048)
			(end 0.67945 -0.305054)
			(stroke
				(width 0.1)
				(type default)
			)
			(layer "B.Fab")
		)
		(fp_line
			(start -0.120396 0.2794)
			(end 0.12065 0.2794)
			(stroke
				(width 0.1)
				(type default)
			)
			(layer "B.Fab")
		)
		(fp_line
			(start 0.12065 0.2794)
			(end 0.12065 0.3048)
			(stroke
				(width 0.1)
				(type default)
			)
			(layer "B.Fab")
		)
		(fp_line
			(start -0.12065 -0.2794)
			(end -0.12065 -0.3048)
			(stroke
				(width 0.1)
				(type default)
			)
			(layer "B.Fab")
		)
		(fp_line
			(start 0.12065 -0.2794)
			(end -0.12065 -0.2794)
			(stroke
				(width 0.1)
				(type default)
			)
			(layer "B.Fab")
		)
		(fp_line
			(start -0.67945 -0.3048)
			(end -0.67945 0.3048)
			(stroke
				(width 0.1)
				(type default)
			)
			(layer "B.Fab")
		)
		(fp_line
			(start -0.12065 -0.3048)
			(end -0.67945 -0.3048)
			(stroke
				(width 0.1)
				(type default)
			)
			(layer "B.Fab")
		)
		(fp_line
			(start 0.12065 -0.305054)
			(end 0.12065 -0.2794)
			(stroke
				(width 0.1)
				(type default)
			)
			(layer "B.Fab")
		)
		(fp_line
			(start 0.67945 -0.305054)
			(end 0.12065 -0.305054)
			(stroke
				(width 0.1)
				(type default)
			)
			(layer "B.Fab")
		)
		(pad "1" smd circle
			(at 0.40005 0 90)
			(size 0 0)
			(layers "B.Cu" "B.Mask" "B.Paste")
			(net "PVCCIN_CPU1_PVCC")
		)
		(pad "2" smd circle
			(at -0.40005 0 90)
			(size 0 0)
			(layers "B.Cu" "B.Mask" "B.Paste")
			(net "PVCCIN_CPU1_VDD1")
		)
	)
	(footprint ""
		(layer "B.Cu")
		(at 291.588698 -152.176988)
		(property "Reference" "R691"
			(at 0 0 0)
			(layer "B.SilkS")
			(hide yes)
			(effects
				(font
					(size 1.27 1.27)
				)
				(justify mirror)
			)
		)
		(property "Value" ""
			(at 0 0 0)
			(layer "B.Fab")
			(effects
				(font
					(size 1.27 1.27)
				)
				(justify mirror)
			)
		)
		(duplicate_pad_numbers_are_jumpers no)
		(fp_line
			(start -0.7874 -0.4064)
			(end -0.7874 0.4064)
			(stroke
				(width 0.1524)
				(type default)
			)
			(layer "B.SilkS")
		)
		(fp_line
			(start -0.7874 0.4064)
			(end 0.7874 0.4064)
			(stroke
				(width 0.1524)
				(type default)
			)
			(layer "B.SilkS")
		)
		(fp_line
			(start 0.7874 -0.4064)
			(end -0.7874 -0.4064)
			(stroke
				(width 0.1524)
				(type default)
			)
			(layer "B.SilkS")
		)
		(fp_line
			(start 0.7874 0.4064)
			(end 0.7874 -0.4064)
			(stroke
				(width 0.1524)
				(type default)
			)
			(layer "B.SilkS")
		)
		(fp_line
			(start -0.67945 -0.3048)
			(end -0.67945 0.3048)
			(stroke
				(width 0.1)
				(type default)
			)
			(layer "B.Fab")
		)
		(fp_line
			(start -0.67945 0.3048)
			(end -0.120396 0.3048)
			(stroke
				(width 0.1)
				(type default)
			)
			(layer "B.Fab")
		)
		(fp_line
			(start -0.12065 -0.3048)
			(end -0.67945 -0.3048)
			(stroke
				(width 0.1)
				(type default)
			)
			(layer "B.Fab")
		)
		(fp_line
			(start -0.12065 -0.2794)
			(end -0.12065 -0.3048)
			(stroke
				(width 0.1)
				(type default)
			)
			(layer "B.Fab")
		)
		(fp_line
			(start -0.120396 0.2794)
			(end 0.12065 0.2794)
			(stroke
				(width 0.1)
				(type default)
			)
			(layer "B.Fab")
		)
		(fp_line
			(start -0.120396 0.3048)
			(end -0.120396 0.2794)
			(stroke
				(width 0.1)
				(type default)
			)
			(layer "B.Fab")
		)
		(fp_line
			(start 0.12065 -0.305054)
			(end 0.12065 -0.2794)
			(stroke
				(width 0.1)
				(type default)
			)
			(layer "B.Fab")
		)
		(fp_line
			(start 0.12065 -0.2794)
			(end -0.12065 -0.2794)
			(stroke
				(width 0.1)
				(type default)
			)
			(layer "B.Fab")
		)
		(fp_line
			(start 0.12065 0.2794)
			(end 0.12065 0.3048)
			(stroke
				(width 0.1)
				(type default)
			)
			(layer "B.Fab")
		)
		(fp_line
			(start 0.12065 0.3048)
			(end 0.67945 0.3048)
			(stroke
				(width 0.1)
				(type default)
			)
			(layer "B.Fab")
		)
		(fp_line
			(start 0.67945 -0.305054)
			(end 0.12065 -0.305054)
			(stroke
				(width 0.1)
				(type default)
			)
			(layer "B.Fab")
		)
		(fp_line
			(start 0.67945 0.3048)
			(end 0.67945 -0.305054)
			(stroke
				(width 0.1)
				(type default)
			)
			(layer "B.Fab")
		)
		(pad "1" smd circle
			(at 0.40005 0 180)
			(size 0 0)
			(layers "B.Cu" "B.Mask" "B.Paste")
			(net "I3C_SPD_DDRABCD_CPU0_LVC1_R_SCL")
		)
		(pad "2" smd circle
			(at -0.40005 0 180)
			(size 0 0)
			(layers "B.Cu" "B.Mask" "B.Paste")
			(net "I3C_SPD_DDRABCD_CPU0_LVC1_SCL")
		)
	)
)
